# BASEBOARD_FAB2 (Tioga Pass) — schematic netlist excerpt (pin names and nets, part order shuffled) for the footprints in the layout excerpt that follows; sources: Cadence DE-HDL packaged netlist, KiCad conversion of Wiwynn_Tioga_Pass_MB.brd

C25W32  CAP  1.0UF 16V 10% X6S  pkg 0402  page 149 : A = VCC_ADCAV3V3 ; B = GND
R3P56  RES  1.00K 1% CHIP  pkg 0402  page 156 : A = FM_CPU0_SM_WP ; B = GND
C3U4  CAP  10UF 16V 10% X6S  pkg 0805  page 216 : A = VR_FET_SW_P12V_STBY_PVDDQ_ABC ; B = GND

(kicad_pcb
	(version 20260206)
	(generator "pcbnew")
	(generator_version "10.0")
	(general
		(thickness 1.6)
		(legacy_teardrops no)
	)
	(paper "A4")
	(title_block
		(title "Wiwynn_Tioga_Pass_MB.brd")
		(comment 1 "Tioga Pass / footprints 3022-3024 of 4770")
	)
	(layers
		(0 "F.Cu" signal "TOP")
		(4 "In1.Cu" signal "L2GND")
		(6 "In2.Cu" signal "L3")
		(8 "In3.Cu" signal "L4GND")
		(10 "In4.Cu" signal "L5")
		(12 "In5.Cu" signal "L6GND")
		(14 "In6.Cu" signal "L7VCC")
		(16 "In7.Cu" signal "L8VCC")
		(18 "In8.Cu" signal "L9GND")
		(20 "In9.Cu" signal "L10")
		(22 "In10.Cu" signal "L11GND")
		(24 "In11.Cu" signal "L12")
		(26 "In12.Cu" signal "L13GND")
		(2 "B.Cu" signal "BOTTOM")
		(9 "F.Adhes" user "F.Adhesive")
		(11 "B.Adhes" user "B.Adhesive")
		(13 "F.Paste" user "Package Geometry/Pastemask Top")
		(15 "B.Paste" user "Package Geometry/Pastemask Bottom")
		(5 "F.SilkS" user "Ref Des/Silkscreen Top")
		(7 "B.SilkS" user "Ref Des/Silkscreen Bottom")
		(1 "F.Mask" user "Board Geometry/Soldermask Top")
		(3 "B.Mask" user "Board Geometry/Soldermask Bottom")
		(17 "Dwgs.User" user "User.Drawings")
		(19 "Cmts.User" user "User.Comments")
		(21 "Eco1.User" user "User.Eco1")
		(23 "Eco2.User" user "User.Eco2")
		(25 "Edge.Cuts" user "Board Geometry/Outline")
		(27 "Margin" user)
		(31 "F.CrtYd" user "Package Geometry/Place Bound Top")
		(29 "B.CrtYd" user "Package Geometry/Place Bound Bottom")
		(35 "F.Fab" user "Ref Des/Assembly Top")
		(33 "B.Fab" user "Ref Des/Assembly Bottom")
	)
	(footprint ""
		(layer "B.Cu")
		(at 335.89722 -84.82584 180)
		(property "Reference" "R3P56"
			(at 0 0 0)
			(layer "B.SilkS")
			(hide yes)
			(effects
				(font
					(size 1.27 1.27)
				)
				(justify mirror)
			)
		)
		(property "Value" ""
			(at 0 0 0)
			(layer "B.Fab")
			(effects
				(font
					(size 1.27 1.27)
				)
				(justify mirror)
			)
		)
		(duplicate_pad_numbers_are_jumpers no)
		(fp_poly
			(pts
				(xy 0.2794 -0.1016) (xy -0.2794 -0.1016) (xy -0.2794 0.9906) (xy 0.2794 0.9906)
			)
			(stroke
				(width 0)
				(type default)
			)
			(fill no)
			(layer "B.CrtYd")
		)
		(fp_line
			(start 0.2794 0.9906)
			(end -0.2794 0.9906)
			(stroke
				(width 0.1)
				(type default)
			)
			(layer "B.Fab")
		)
		(fp_line
			(start 0.2794 -0.1016)
			(end 0.2794 0.9906)
			(stroke
				(width 0.1)
				(type default)
			)
			(layer "B.Fab")
		)
		(fp_line
			(start -0.2794 0.9906)
			(end -0.2794 -0.1016)
			(stroke
				(width 0.1)
				(type default)
			)
			(layer "B.Fab")
		)
		(fp_line
			(start -0.2794 -0.1016)
			(end 0.2794 -0.1016)
			(stroke
				(width 0.1)
				(type default)
			)
			(layer "B.Fab")
		)
		(pad "1" smd rect
			(at 0 0)
			(size 0.508 0.508)
			(layers "B.Cu" "B.Mask" "B.Paste")
			(net "FM_CPU0_SM_WP")
		)
		(pad "2" smd rect
			(at 0 0.889)
			(size 0.508 0.508)
			(layers "B.Cu" "B.Mask" "B.Paste")
			(net "GND")
		)
		(zone
			(layer "B.Cu")
			(hatch none 0.5)
			(connect_pads
				(clearance 0)
			)
			(min_thickness 0.25)
			(keepout
				(tracks not_allowed)
				(vias allowed)
				(pads allowed)
				(copperpour not_allowed)
				(footprints allowed)
			)
			(placement
				(enabled no)
				(sheetname "")
			)
			(fill
				(thermal_gap 0.5)
				(thermal_bridge_width 0.5)
				(island_removal_mode 0)
			)
			(polygon
				(pts
					(xy 335.64322 -85.46084) (xy 336.15122 -85.46084) (xy 336.15122 -85.07984) (xy 335.64322 -85.07984)
				)
			)
		)
		(zone
			(layer "B.Cu")
			(hatch none 0.5)
			(connect_pads
				(clearance 0)
			)
			(min_thickness 0.25)
			(keepout
				(tracks allowed)
				(vias not_allowed)
				(pads allowed)
				(copperpour not_allowed)
				(footprints allowed)
			)
			(placement
				(enabled no)
				(sheetname "")
			)
			(fill
				(thermal_gap 0.5)
				(thermal_bridge_width 0.5)
				(island_removal_mode 0)
			)
			(polygon
				(pts
					(xy 335.64322 -85.07984) (xy 336.15122 -85.07984) (xy 336.15122 -85.46084) (xy 335.64322 -85.46084)
				)
			)
		)
	)
	(footprint ""
		(layer "B.Cu")
		(at 347.5736 -3.8608 -90)
		(property "Reference" "C3U4"
			(at 0 0 90)
			(layer "B.SilkS")
			(hide yes)
			(effects
				(font
					(size 1.27 1.27)
				)
				(justify mirror)
			)
		)
		(property "Value" ""
			(at 0 0 90)
			(layer "B.Fab")
			(effects
				(font
					(size 1.27 1.27)
				)
				(justify mirror)
			)
		)
		(duplicate_pad_numbers_are_jumpers no)
		(fp_rect
			(start 0.7239 1.9939)
			(end -0.7239 -0.2159)
			(stroke
				(width 0)
				(type default)
			)
			(fill no)
			(layer "B.CrtYd")
		)
		(fp_line
			(start -0.7239 1.9939)
			(end -0.7239 -0.2159)
			(stroke
				(width 0.1)
				(type default)
			)
			(layer "B.Fab")
		)
		(fp_line
			(start 0.7239 1.9939)
			(end -0.7239 1.9939)
			(stroke
				(width 0.1)
				(type default)
			)
			(layer "B.Fab")
		)
		(fp_line
			(start -0.7239 -0.2159)
			(end 0.7239 -0.2159)
			(stroke
				(width 0.1)
				(type default)
			)
			(layer "B.Fab")
		)
		(fp_line
			(start 0.7239 -0.2159)
			(end 0.7239 1.9939)
			(stroke
				(width 0.1)
				(type default)
			)
			(layer "B.Fab")
		)
		(pad "1" smd rect
			(at 0 0 90)
			(size 1.27 1.016)
			(layers "B.Cu" "B.Mask" "B.Paste")
			(net "VR_FET_SW_P12V_STBY_PVDDQ_ABC")
		)
		(pad "2" smd rect
			(at 0 1.778 90)
			(size 1.27 1.016)
			(layers "B.Cu" "B.Mask" "B.Paste")
			(net "GND")
		)
		(zone
			(layer "B.Cu")
			(hatch none 0.5)
			(connect_pads
				(clearance 0)
			)
			(min_thickness 0.25)
			(keepout
				(tracks not_allowed)
				(vias allowed)
				(pads allowed)
				(copperpour not_allowed)
				(footprints allowed)
			)
			(placement
				(enabled no)
				(sheetname "")
			)
			(fill
				(thermal_gap 0.5)
				(thermal_bridge_width 0.5)
				(island_removal_mode 0)
			)
			(polygon
				(pts
					(xy 346.3036 -3.2258) (xy 347.0656 -3.2258) (xy 347.0656 -4.4958) (xy 346.3036 -4.4958)
				)
			)
		)
	)
	(footprint ""
		(layer "B.Cu")
		(at 413.0675 -24.384 -90)
		(property "Reference" "C25W32"
			(at 0.8382 -0.67818 270)
			(unlocked yes)
			(layer "B.SilkS")
			(effects
				(font
					(size 0.4064 0.254)
					(thickness 0.1524)
				)
				(justify left mirror)
			)
		)
		(property "Value" ""
			(at 0 0 90)
			(layer "B.Fab")
			(effects
				(font
					(size 1.27 1.27)
				)
				(justify mirror)
			)
		)
		(duplicate_pad_numbers_are_jumpers no)
		(fp_poly
			(pts
				(xy -0.3048 -0.1016) (xy -0.3048 0.9906) (xy 0.3048 0.9906) (xy 0.3048 -0.1016)
			)
			(stroke
				(width 0)
				(type default)
			)
			(fill no)
			(layer "B.CrtYd")
		)
		(fp_line
			(start -0.3048 0.9906)
			(end -0.3048 -0.1016)
			(stroke
				(width 0.1)
				(type default)
			)
			(layer "B.Fab")
		)
		(fp_line
			(start 0.3048 0.9906)
			(end -0.3048 0.9906)
			(stroke
				(width 0.1)
				(type default)
			)
			(layer "B.Fab")
		)
		(fp_line
			(start -0.3048 -0.1016)
			(end 0.3048 -0.1016)
			(stroke
				(width 0.1)
				(type default)
			)
			(layer "B.Fab")
		)
		(fp_line
			(start 0.3048 -0.1016)
			(end 0.3048 0.9906)
			(stroke
				(width 0.1)
				(type default)
			)
			(layer "B.Fab")
		)
		(pad "1" smd rect
			(at 0 0 90)
			(size 0.508 0.508)
			(layers "B.Cu" "B.Mask" "B.Paste")
			(net "VCC_ADCAV3V3")
		)
		(pad "2" smd rect
			(at 0 0.889 90)
			(size 0.508 0.508)
			(layers "B.Cu" "B.Mask" "B.Paste")
			(net "GND")
		)
		(zone
			(layer "B.Cu")
			(hatch none 0.5)
			(connect_pads
				(clearance 0)
			)
			(min_thickness 0.25)
			(keepout
				(tracks not_allowed)
				(vias allowed)
				(pads allowed)
				(copperpour not_allowed)
				(footprints allowed)
			)
			(placement
				(enabled no)
				(sheetname "")
			)
			(fill
				(thermal_gap 0.5)
				(thermal_bridge_width 0.5)
				(island_removal_mode 0)
			)
			(polygon
				(pts
					(xy 412.4325 -24.13) (xy 412.4325 -24.638) (xy 412.8135 -24.638) (xy 412.8135 -24.13)
				)
			)
		)
		(zone
			(layer "B.Cu")
			(hatch none 0.5)
			(connect_pads
				(clearance 0)
			)
			(min_thickness 0.25)
			(keepout
				(tracks allowed)
				(vias not_allowed)
				(pads allowed)
				(copperpour not_allowed)
				(footprints allowed)
			)
			(placement
				(enabled no)
				(sheetname "")
			)
			(fill
				(thermal_gap 0.5)
				(thermal_bridge_width 0.5)
				(island_removal_mode 0)
			)
			(polygon
				(pts
					(xy 412.8135 -24.13) (xy 412.8135 -24.638) (xy 412.4325 -24.638) (xy 412.4325 -24.13)
				)
			)
		)
	)
)
